(kicad_pcb
	(version 20260206)
	(generator "pcbnew")
	(generator_version "10.0")
	(general
		(thickness 1.6)
		(legacy_teardrops no)
	)
	(paper "A4")
	(title_block
		(title "04192023_DAF0TMB3IC0_F0TG_MB_C_brd_V02_OCP.brd")
		(comment 1 "Grand Teton / footprints 4262-4269 of 8354")
	)
	(layers
		(0 "F.Cu" signal "TOP")
		(4 "In1.Cu" signal "GND")
		(6 "In2.Cu" signal "IN1")
		(8 "In3.Cu" signal "GND1")
		(10 "In4.Cu" signal "IN2")
		(12 "In5.Cu" signal "GND2")
		(14 "In6.Cu" signal "IN3")
		(16 "In7.Cu" signal "GND3")
		(18 "In8.Cu" signal "VCC")
		(20 "In9.Cu" signal "VCC1")
		(22 "In10.Cu" signal "GND4")
		(24 "In11.Cu" signal "IN4")
		(26 "In12.Cu" signal "GND5")
		(28 "In13.Cu" signal "IN5")
		(30 "In14.Cu" signal "GND6")
		(32 "In15.Cu" signal "IN6")
		(34 "In16.Cu" signal "GND7")
		(2 "B.Cu" signal "BOTTOM")
		(9 "F.Adhes" user "F.Adhesive")
		(11 "B.Adhes" user "B.Adhesive")
		(13 "F.Paste" user "Package Geometry/Pastemask Top")
		(15 "B.Paste" user "Package Geometry/Pastemask Bottom")
		(5 "F.SilkS" user "Ref Des/Silkscreen Top")
		(7 "B.SilkS" user "Ref Des/Silkscreen Bottom")
		(1 "F.Mask" user "Board Geometry/Soldermask Top")
		(3 "B.Mask" user "Board Geometry/Soldermask Bottom")
		(17 "Dwgs.User" user "User.Drawings")
		(19 "Cmts.User" user "User.Comments")
		(21 "Eco1.User" user "User.Eco1")
		(23 "Eco2.User" user "User.Eco2")
		(25 "Edge.Cuts" user "Board Geometry/Outline")
		(27 "Margin" user)
		(31 "F.CrtYd" user "Package Geometry/Place Bound Top")
		(29 "B.CrtYd" user "Package Geometry/Place Bound Bottom")
		(35 "F.Fab" user "Ref Des/Assembly Top")
		(33 "B.Fab" user "Ref Des/Assembly Bottom")
	)
	(footprint ""
		(layer "F.Cu")
		(at 146.927316 -21.498306 -90)
		(property "Reference" "R8101"
			(at 0 0 270)
			(layer "F.SilkS")
			(hide yes)
			(effects
				(font
					(size 1.27 1.27)
				)
			)
		)
		(property "Value" ""
			(at 0 0 270)
			(layer "F.Fab")
			(effects
				(font
					(size 1.27 1.27)
				)
			)
		)
		(duplicate_pad_numbers_are_jumpers no)
		(fp_line
			(start -0.7874 0.4064)
			(end -0.7874 -0.4064)
			(stroke
				(width 0.1524)
				(type default)
			)
			(layer "F.SilkS")
		)
		(fp_line
			(start 0.7874 0.4064)
			(end -0.7874 0.4064)
			(stroke
				(width 0.1524)
				(type default)
			)
			(layer "F.SilkS")
		)
		(fp_line
			(start -0.7874 -0.4064)
			(end 0.7874 -0.4064)
			(stroke
				(width 0.1524)
				(type default)
			)
			(layer "F.SilkS")
		)
		(fp_line
			(start 0.7874 -0.4064)
			(end 0.7874 0.4064)
			(stroke
				(width 0.1524)
				(type default)
			)
			(layer "F.SilkS")
		)
		(fp_line
			(start -0.67945 0.3048)
			(end -0.67945 -0.305054)
			(stroke
				(width 0.1)
				(type default)
			)
			(layer "F.Fab")
		)
		(fp_line
			(start -0.12065 0.3048)
			(end -0.67945 0.3048)
			(stroke
				(width 0.1)
				(type default)
			)
			(layer "F.Fab")
		)
		(fp_line
			(start 0.120396 0.3048)
			(end 0.120396 0.2794)
			(stroke
				(width 0.1)
				(type default)
			)
			(layer "F.Fab")
		)
		(fp_line
			(start 0.67945 0.3048)
			(end 0.120396 0.3048)
			(stroke
				(width 0.1)
				(type default)
			)
			(layer "F.Fab")
		)
		(fp_line
			(start -0.12065 0.2794)
			(end -0.12065 0.3048)
			(stroke
				(width 0.1)
				(type default)
			)
			(layer "F.Fab")
		)
		(fp_line
			(start 0.120396 0.2794)
			(end -0.12065 0.2794)
			(stroke
				(width 0.1)
				(type default)
			)
			(layer "F.Fab")
		)
		(fp_line
			(start -0.12065 -0.2794)
			(end 0.12065 -0.2794)
			(stroke
				(width 0.1)
				(type default)
			)
			(layer "F.Fab")
		)
		(fp_line
			(start 0.12065 -0.2794)
			(end 0.12065 -0.3048)
			(stroke
				(width 0.1)
				(type default)
			)
			(layer "F.Fab")
		)
		(fp_line
			(start 0.12065 -0.3048)
			(end 0.67945 -0.3048)
			(stroke
				(width 0.1)
				(type default)
			)
			(layer "F.Fab")
		)
		(fp_line
			(start 0.67945 -0.3048)
			(end 0.67945 0.3048)
			(stroke
				(width 0.1)
				(type default)
			)
			(layer "F.Fab")
		)
		(fp_line
			(start -0.67945 -0.305054)
			(end -0.12065 -0.305054)
			(stroke
				(width 0.1)
				(type default)
			)
			(layer "F.Fab")
		)
		(fp_line
			(start -0.12065 -0.305054)
			(end -0.12065 -0.2794)
			(stroke
				(width 0.1)
				(type default)
			)
			(layer "F.Fab")
		)
		(pad "1" smd circle
			(at -0.40005 0 270)
			(size 0 0)
			(layers "F.Cu" "F.Mask" "F.Paste")
			(net "FM_AC_PWR_BTN_R_N")
		)
		(pad "2" smd circle
			(at 0.40005 0 270)
			(size 0 0)
			(layers "F.Cu" "F.Mask" "F.Paste")
			(net "FM_AC_PWR_BTN_N")
		)
	)
	(footprint ""
		(layer "F.Cu")
		(at 422.688258 -171.231306 90)
		(property "Reference" "PL62"
			(at -3.10134 4.124452 90)
			(unlocked yes)
			(layer "F.SilkS")
			(effects
				(font
					(size 0.7874 0.5842)
					(thickness 0.1524)
				)
				(justify left)
			)
		)
		(property "Value" ""
			(at 0 0 90)
			(layer "F.Fab")
			(effects
				(font
					(size 1.27 1.27)
				)
			)
		)
		(duplicate_pad_numbers_are_jumpers no)
		(fp_line
			(start 3.24993 -3.24993)
			(end 3.24993 -2.2352)
			(stroke
				(width 0.1524)
				(type default)
			)
			(layer "F.SilkS")
		)
		(fp_line
			(start -3.24993 -3.24993)
			(end 3.24993 -3.24993)
			(stroke
				(width 0.1524)
				(type default)
			)
			(layer "F.SilkS")
		)
		(fp_line
			(start -3.24993 -2.2352)
			(end -3.24993 -3.24993)
			(stroke
				(width 0.1524)
				(type default)
			)
			(layer "F.SilkS")
		)
		(fp_line
			(start 3.24993 2.761742)
			(end 3.24993 3.24993)
			(stroke
				(width 0.1524)
				(type default)
			)
			(layer "F.SilkS")
		)
		(fp_line
			(start 3.24993 3.24993)
			(end -3.24993 3.24993)
			(stroke
				(width 0.1524)
				(type default)
			)
			(layer "F.SilkS")
		)
		(fp_line
			(start -3.24993 3.24993)
			(end -3.24993 2.2352)
			(stroke
				(width 0.1524)
				(type default)
			)
			(layer "F.SilkS")
		)
		(fp_line
			(start 3.24993 -3.24993)
			(end 3.24993 3.24993)
			(stroke
				(width 0.1)
				(type default)
			)
			(layer "F.Fab")
		)
		(fp_line
			(start -3.24993 -3.24993)
			(end 3.24993 -3.24993)
			(stroke
				(width 0.1)
				(type default)
			)
			(layer "F.Fab")
		)
		(fp_line
			(start 3.24993 3.24993)
			(end -3.24993 3.24993)
			(stroke
				(width 0.1)
				(type default)
			)
			(layer "F.Fab")
		)
		(fp_line
			(start -3.24993 3.24993)
			(end -3.24993 -3.24993)
			(stroke
				(width 0.1)
				(type default)
			)
			(layer "F.Fab")
		)
		(pad "1" smd rect
			(at -2.29997 0 90)
			(size 2.0066 4.2164)
			(layers "F.Cu" "F.Mask" "F.Paste")
			(net "GND")
		)
		(pad "2" smd rect
			(at 2.29997 0 90)
			(size 2.0066 4.2164)
			(layers "F.Cu" "F.Mask" "F.Paste")
			(net "IND_SOC_P0_CPL0")
		)
	)
	(footprint ""
		(layer "F.Cu")
		(at 214.432134 -47.335948 90)
		(property "Reference" "R3588"
			(at 0 0 90)
			(layer "F.SilkS")
			(hide yes)
			(effects
				(font
					(size 1.27 1.27)
				)
			)
		)
		(property "Value" ""
			(at 0 0 90)
			(layer "F.Fab")
			(effects
				(font
					(size 1.27 1.27)
				)
			)
		)
		(duplicate_pad_numbers_are_jumpers no)
		(fp_line
			(start 0.7874 -0.4064)
			(end 0.7874 0.4064)
			(stroke
				(width 0.1524)
				(type default)
			)
			(layer "F.SilkS")
		)
		(fp_line
			(start -0.7874 -0.4064)
			(end 0.7874 -0.4064)
			(stroke
				(width 0.1524)
				(type default)
			)
			(layer "F.SilkS")
		)
		(fp_line
			(start 0.7874 0.4064)
			(end -0.7874 0.4064)
			(stroke
				(width 0.1524)
				(type default)
			)
			(layer "F.SilkS")
		)
		(fp_line
			(start -0.7874 0.4064)
			(end -0.7874 -0.4064)
			(stroke
				(width 0.1524)
				(type default)
			)
			(layer "F.SilkS")
		)
		(fp_line
			(start -0.12065 -0.305054)
			(end -0.12065 -0.2794)
			(stroke
				(width 0.1)
				(type default)
			)
			(layer "F.Fab")
		)
		(fp_line
			(start -0.67945 -0.305054)
			(end -0.12065 -0.305054)
			(stroke
				(width 0.1)
				(type default)
			)
			(layer "F.Fab")
		)
		(fp_line
			(start 0.67945 -0.3048)
			(end 0.67945 0.3048)
			(stroke
				(width 0.1)
				(type default)
			)
			(layer "F.Fab")
		)
		(fp_line
			(start 0.12065 -0.3048)
			(end 0.67945 -0.3048)
			(stroke
				(width 0.1)
				(type default)
			)
			(layer "F.Fab")
		)
		(fp_line
			(start 0.12065 -0.2794)
			(end 0.12065 -0.3048)
			(stroke
				(width 0.1)
				(type default)
			)
			(layer "F.Fab")
		)
		(fp_line
			(start -0.12065 -0.2794)
			(end 0.12065 -0.2794)
			(stroke
				(width 0.1)
				(type default)
			)
			(layer "F.Fab")
		)
		(fp_line
			(start 0.120396 0.2794)
			(end -0.12065 0.2794)
			(stroke
				(width 0.1)
				(type default)
			)
			(layer "F.Fab")
		)
		(fp_line
			(start -0.12065 0.2794)
			(end -0.12065 0.3048)
			(stroke
				(width 0.1)
				(type default)
			)
			(layer "F.Fab")
		)
		(fp_line
			(start 0.67945 0.3048)
			(end 0.120396 0.3048)
			(stroke
				(width 0.1)
				(type default)
			)
			(layer "F.Fab")
		)
		(fp_line
			(start 0.120396 0.3048)
			(end 0.120396 0.2794)
			(stroke
				(width 0.1)
				(type default)
			)
			(layer "F.Fab")
		)
		(fp_line
			(start -0.12065 0.3048)
			(end -0.67945 0.3048)
			(stroke
				(width 0.1)
				(type default)
			)
			(layer "F.Fab")
		)
		(fp_line
			(start -0.67945 0.3048)
			(end -0.67945 -0.305054)
			(stroke
				(width 0.1)
				(type default)
			)
			(layer "F.Fab")
		)
		(pad "1" smd circle
			(at -0.40005 0 90)
			(size 0 0)
			(layers "F.Cu" "F.Mask" "F.Paste")
			(net "SMB_INA230_3V3AUX_SCL")
		)
		(pad "2" smd circle
			(at 0.40005 0 90)
			(size 0 0)
			(layers "F.Cu" "F.Mask" "F.Paste")
			(net "SMB_INA230_2_3V3AUX_SCL_R")
		)
	)
	(footprint ""
		(layer "F.Cu")
		(at 386.511292 -381.41783 -90)
		(property "Reference" "C879"
			(at 0 0 270)
			(layer "F.SilkS")
			(hide yes)
			(effects
				(font
					(size 1.27 1.27)
				)
			)
		)
		(property "Value" ""
			(at 0 0 270)
			(layer "F.Fab")
			(effects
				(font
					(size 1.27 1.27)
				)
			)
		)
		(duplicate_pad_numbers_are_jumpers no)
		(fp_line
			(start -0.299974 0.150114)
			(end -0.299974 -0.150114)
			(stroke
				(width 0.1)
				(type default)
			)
			(layer "F.Fab")
		)
		(fp_line
			(start 0.299974 0.150114)
			(end -0.299974 0.150114)
			(stroke
				(width 0.1)
				(type default)
			)
			(layer "F.Fab")
		)
		(fp_line
			(start -0.299974 -0.150114)
			(end 0.299974 -0.150114)
			(stroke
				(width 0.1)
				(type default)
			)
			(layer "F.Fab")
		)
		(fp_line
			(start 0.299974 -0.150114)
			(end 0.299974 0.150114)
			(stroke
				(width 0.1)
				(type default)
			)
			(layer "F.Fab")
		)
		(pad "1" smd rect
			(at -0.2667 0 270)
			(size 0.3048 0.381)
			(layers "F.Cu" "F.Mask" "F.Paste")
			(net "P5E_CPU0_P3_TX_C_DP<11>")
		)
		(pad "2" smd rect
			(at 0.2667 0 270)
			(size 0.3048 0.381)
			(layers "F.Cu" "F.Mask" "F.Paste")
			(net "P5E_CPU0_P3_TX_DP<11>")
		)
	)
	(footprint ""
		(layer "F.Cu")
		(at 101.413056 -31.786576 90)
		(property "Reference" "R6328"
			(at 0 0 90)
			(layer "F.SilkS")
			(hide yes)
			(effects
				(font
					(size 1.27 1.27)
				)
			)
		)
		(property "Value" ""
			(at 0 0 90)
			(layer "F.Fab")
			(effects
				(font
					(size 1.27 1.27)
				)
			)
		)
		(duplicate_pad_numbers_are_jumpers no)
		(fp_line
			(start 0.7874 -0.4064)
			(end 0.7874 0.4064)
			(stroke
				(width 0.1524)
				(type default)
			)
			(layer "F.SilkS")
		)
		(fp_line
			(start -0.7874 -0.4064)
			(end 0.7874 -0.4064)
			(stroke
				(width 0.1524)
				(type default)
			)
			(layer "F.SilkS")
		)
		(fp_line
			(start 0.7874 0.4064)
			(end -0.7874 0.4064)
			(stroke
				(width 0.1524)
				(type default)
			)
			(layer "F.SilkS")
		)
		(fp_line
			(start -0.7874 0.4064)
			(end -0.7874 -0.4064)
			(stroke
				(width 0.1524)
				(type default)
			)
			(layer "F.SilkS")
		)
		(fp_line
			(start -0.12065 -0.305054)
			(end -0.12065 -0.2794)
			(stroke
				(width 0.1)
				(type default)
			)
			(layer "F.Fab")
		)
		(fp_line
			(start -0.67945 -0.305054)
			(end -0.12065 -0.305054)
			(stroke
				(width 0.1)
				(type default)
			)
			(layer "F.Fab")
		)
		(fp_line
			(start 0.67945 -0.3048)
			(end 0.67945 0.3048)
			(stroke
				(width 0.1)
				(type default)
			)
			(layer "F.Fab")
		)
		(fp_line
			(start 0.12065 -0.3048)
			(end 0.67945 -0.3048)
			(stroke
				(width 0.1)
				(type default)
			)
			(layer "F.Fab")
		)
		(fp_line
			(start 0.12065 -0.2794)
			(end 0.12065 -0.3048)
			(stroke
				(width 0.1)
				(type default)
			)
			(layer "F.Fab")
		)
		(fp_line
			(start -0.12065 -0.2794)
			(end 0.12065 -0.2794)
			(stroke
				(width 0.1)
				(type default)
			)
			(layer "F.Fab")
		)
		(fp_line
			(start 0.120396 0.2794)
			(end -0.12065 0.2794)
			(stroke
				(width 0.1)
				(type default)
			)
			(layer "F.Fab")
		)
		(fp_line
			(start -0.12065 0.2794)
			(end -0.12065 0.3048)
			(stroke
				(width 0.1)
				(type default)
			)
			(layer "F.Fab")
		)
		(fp_line
			(start 0.67945 0.3048)
			(end 0.120396 0.3048)
			(stroke
				(width 0.1)
				(type default)
			)
			(layer "F.Fab")
		)
		(fp_line
			(start 0.120396 0.3048)
			(end 0.120396 0.2794)
			(stroke
				(width 0.1)
				(type default)
			)
			(layer "F.Fab")
		)
		(fp_line
			(start -0.12065 0.3048)
			(end -0.67945 0.3048)
			(stroke
				(width 0.1)
				(type default)
			)
			(layer "F.Fab")
		)
		(fp_line
			(start -0.67945 0.3048)
			(end -0.67945 -0.305054)
			(stroke
				(width 0.1)
				(type default)
			)
			(layer "F.Fab")
		)
		(pad "1" smd circle
			(at -0.40005 0 90)
			(size 0 0)
			(layers "F.Cu" "F.Mask" "F.Paste")
			(net "RST_USB_HUB_N")
		)
		(pad "2" smd circle
			(at 0.40005 0 90)
			(size 0 0)
			(layers "F.Cu" "F.Mask" "F.Paste")
			(net "USB_HUB2_TI_GRSTZ_MRP_PROG_FUNC1")
		)
	)
	(footprint ""
		(layer "F.Cu")
		(at 102.268782 -376.067828)
		(property "Reference" "C712"
			(at 0 0 0)
			(layer "F.SilkS")
			(hide yes)
			(effects
				(font
					(size 1.27 1.27)
				)
			)
		)
		(property "Value" ""
			(at 0 0 0)
			(layer "F.Fab")
			(effects
				(font
					(size 1.27 1.27)
				)
			)
		)
		(duplicate_pad_numbers_are_jumpers no)
		(fp_line
			(start -0.299974 -0.150114)
			(end 0.299974 -0.150114)
			(stroke
				(width 0.1)
				(type default)
			)
			(layer "F.Fab")
		)
		(fp_line
			(start -0.299974 0.150114)
			(end -0.299974 -0.150114)
			(stroke
				(width 0.1)
				(type default)
			)
			(layer "F.Fab")
		)
		(fp_line
			(start 0.299974 -0.150114)
			(end 0.299974 0.150114)
			(stroke
				(width 0.1)
				(type default)
			)
			(layer "F.Fab")
		)
		(fp_line
			(start 0.299974 0.150114)
			(end -0.299974 0.150114)
			(stroke
				(width 0.1)
				(type default)
			)
			(layer "F.Fab")
		)
		(pad "1" smd rect
			(at -0.2667 0)
			(size 0.3048 0.381)
			(layers "F.Cu" "F.Mask" "F.Paste")
			(net "P5E_CPU1_P1_TX_C_DN<14>")
		)
		(pad "2" smd rect
			(at 0.2667 0)
			(size 0.3048 0.381)
			(layers "F.Cu" "F.Mask" "F.Paste")
			(net "P5E_CPU1_P1_TX_DN<14>")
		)
	)
	(footprint ""
		(layer "F.Cu")
		(at 398.389348 -17.624298 90)
		(property "Reference" "C41"
			(at 0 0 90)
			(layer "F.SilkS")
			(hide yes)
			(effects
				(font
					(size 1.27 1.27)
				)
			)
		)
		(property "Value" ""
			(at 0 0 90)
			(layer "F.Fab")
			(effects
				(font
					(size 1.27 1.27)
				)
			)
		)
		(duplicate_pad_numbers_are_jumpers no)
		(fp_line
			(start 0.299974 -0.150114)
			(end 0.299974 0.150114)
			(stroke
				(width 0.1)
				(type default)
			)
			(layer "F.Fab")
		)
		(fp_line
			(start -0.299974 -0.150114)
			(end 0.299974 -0.150114)
			(stroke
				(width 0.1)
				(type default)
			)
			(layer "F.Fab")
		)
		(fp_line
			(start 0.299974 0.150114)
			(end -0.299974 0.150114)
			(stroke
				(width 0.1)
				(type default)
			)
			(layer "F.Fab")
		)
		(fp_line
			(start -0.299974 0.150114)
			(end -0.299974 -0.150114)
			(stroke
				(width 0.1)
				(type default)
			)
			(layer "F.Fab")
		)
		(pad "1" smd rect
			(at -0.2667 0 90)
			(size 0.3048 0.381)
			(layers "F.Cu" "F.Mask" "F.Paste")
			(net "P5E_CPU0_G3_TX_C_DN<12>")
		)
		(pad "2" smd rect
			(at 0.2667 0 90)
			(size 0.3048 0.381)
			(layers "F.Cu" "F.Mask" "F.Paste")
			(net "P5E_CPU0_G3_TX_DN<12>")
		)
	)
	(footprint ""
		(layer "F.Cu")
		(at 174.613062 -32.935672 90)
		(property "Reference" "PC2235"
			(at 0 0 90)
			(layer "F.SilkS")
			(hide yes)
			(effects
				(font
					(size 1.27 1.27)
				)
			)
		)
		(property "Value" ""
			(at 0 0 90)
			(layer "F.Fab")
			(effects
				(font
					(size 1.27 1.27)
				)
			)
		)
		(duplicate_pad_numbers_are_jumpers no)
		(fp_line
			(start 0.7874 -0.4064)
			(end 0.7874 0.4064)
			(stroke
				(width 0.1524)
				(type default)
			)
			(layer "F.SilkS")
		)
		(fp_line
			(start -0.7874 -0.4064)
			(end 0.7874 -0.4064)
			(stroke
				(width 0.1524)
				(type default)
			)
			(layer "F.SilkS")
		)
		(fp_line
			(start 0.7874 0.4064)
			(end -0.7874 0.4064)
			(stroke
				(width 0.1524)
				(type default)
			)
			(layer "F.SilkS")
		)
		(fp_line
			(start -0.7874 0.4064)
			(end -0.7874 -0.4064)
			(stroke
				(width 0.1524)
				(type default)
			)
			(layer "F.SilkS")
		)
		(fp_line
			(start -0.12065 -0.305054)
			(end -0.12065 -0.2794)
			(stroke
				(width 0.1)
				(type default)
			)
			(layer "F.Fab")
		)
		(fp_line
			(start -0.67945 -0.305054)
			(end -0.12065 -0.305054)
			(stroke
				(width 0.1)
				(type default)
			)
			(layer "F.Fab")
		)
		(fp_line
			(start 0.67945 -0.3048)
			(end 0.67945 0.3048)
			(stroke
				(width 0.1)
				(type default)
			)
			(layer "F.Fab")
		)
		(fp_line
			(start 0.12065 -0.3048)
			(end 0.67945 -0.3048)
			(stroke
				(width 0.1)
				(type default)
			)
			(layer "F.Fab")
		)
		(fp_line
			(start 0.12065 -0.2794)
			(end 0.12065 -0.3048)
			(stroke
				(width 0.1)
				(type default)
			)
			(layer "F.Fab")
		)
		(fp_line
			(start -0.12065 -0.2794)
			(end 0.12065 -0.2794)
			(stroke
				(width 0.1)
				(type default)
			)
			(layer "F.Fab")
		)
		(fp_line
			(start 0.120396 0.2794)
			(end -0.12065 0.2794)
			(stroke
				(width 0.1)
				(type default)
			)
			(layer "F.Fab")
		)
		(fp_line
			(start -0.12065 0.2794)
			(end -0.12065 0.3048)
			(stroke
				(width 0.1)
				(type default)
			)
			(layer "F.Fab")
		)
		(fp_line
			(start 0.67945 0.3048)
			(end 0.120396 0.3048)
			(stroke
				(width 0.1)
				(type default)
			)
			(layer "F.Fab")
		)
		(fp_line
			(start 0.120396 0.3048)
			(end 0.120396 0.2794)
			(stroke
				(width 0.1)
				(type default)
			)
			(layer "F.Fab")
		)
		(fp_line
			(start -0.12065 0.3048)
			(end -0.67945 0.3048)
			(stroke
				(width 0.1)
				(type default)
			)
			(layer "F.Fab")
		)
		(fp_line
			(start -0.67945 0.3048)
			(end -0.67945 -0.305054)
			(stroke
				(width 0.1)
				(type default)
			)
			(layer "F.Fab")
		)
		(pad "1" smd circle
			(at -0.40005 0 90)
			(size 0 0)
			(layers "F.Cu" "F.Mask" "F.Paste")
			(net "P12V_SCM_IMON")
		)
		(pad "2" smd circle
			(at 0.40005 0 90)
			(size 0 0)
			(layers "F.Cu" "F.Mask" "F.Paste")
			(net "GND")
		)
	)
)
